# S9S_MB_2U (Grand Teton) — schematic netlist excerpt (pin names and nets, part order shuffled) for the footprints in the layout excerpt that follows; sources: Cadence DE-HDL packaged netlist, KiCad conversion of 03242023_DA0F0TMBIJ0_F0T_Motherboard_J_brd_V01_OCP.brd

R4695  Q_RES  0 5% CHIP  pkg 0402LF  page 305 : A = SMB_SML1_PMBUS_HSC_SCL ; B = SMB_SML1_PMBUS_HSC_MODULE_SCL
R64  Q_RES  200 1% CHIP  pkg 0402LF  page 44 : A = JTAG_MUX_CPU1_GTL_TDI ; B = JTAG_DBP_CPU1_GTL_R_TDI

(kicad_pcb
	(version 20260206)
	(generator "pcbnew")
	(generator_version "10.0")
	(general
		(thickness 1.6)
		(legacy_teardrops no)
	)
	(paper "A4")
	(title_block
		(title "03242023_DA0F0TMBIJ0_F0T_Motherboard_J_brd_V01_OCP.brd")
		(comment 1 "Grand Teton / footprints 5976-5977 of 6105")
	)
	(layers
		(0 "F.Cu" signal "TOP")
		(4 "In1.Cu" signal "GND")
		(6 "In2.Cu" signal "IN1")
		(8 "In3.Cu" signal "GND1")
		(10 "In4.Cu" signal "IN2")
		(12 "In5.Cu" signal "GND2")
		(14 "In6.Cu" signal "IN3")
		(16 "In7.Cu" signal "GND3")
		(18 "In8.Cu" signal "VCC")
		(20 "In9.Cu" signal "VCC1")
		(22 "In10.Cu" signal "GND4")
		(24 "In11.Cu" signal "IN4")
		(26 "In12.Cu" signal "GND5")
		(28 "In13.Cu" signal "IN5")
		(30 "In14.Cu" signal "GND6")
		(32 "In15.Cu" signal "IN6")
		(34 "In16.Cu" signal "GND7")
		(2 "B.Cu" signal "BOTTOM")
		(9 "F.Adhes" user "F.Adhesive")
		(11 "B.Adhes" user "B.Adhesive")
		(13 "F.Paste" user "Package Geometry/Pastemask Top")
		(15 "B.Paste" user "Package Geometry/Pastemask Bottom")
		(5 "F.SilkS" user "Ref Des/Silkscreen Top")
		(7 "B.SilkS" user "Ref Des/Silkscreen Bottom")
		(1 "F.Mask" user "Board Geometry/Soldermask Top")
		(3 "B.Mask" user "Board Geometry/Soldermask Bottom")
		(17 "Dwgs.User" user "User.Drawings")
		(19 "Cmts.User" user "User.Comments")
		(21 "Eco1.User" user "User.Eco1")
		(23 "Eco2.User" user "User.Eco2")
		(25 "Edge.Cuts" user "Board Geometry/Outline")
		(27 "Margin" user)
		(31 "F.CrtYd" user "Package Geometry/Place Bound Top")
		(29 "B.CrtYd" user "Package Geometry/Place Bound Bottom")
		(35 "F.Fab" user "Ref Des/Assembly Top")
		(33 "B.Fab" user "Ref Des/Assembly Bottom")
	)
	(footprint ""
		(layer "B.Cu")
		(at 97.257108 -190.705232 -90)
		(property "Reference" "R64"
			(at 0 0 90)
			(layer "B.SilkS")
			(hide yes)
			(effects
				(font
					(size 1.27 1.27)
				)
				(justify mirror)
			)
		)
		(property "Value" ""
			(at 0 0 90)
			(layer "B.Fab")
			(effects
				(font
					(size 1.27 1.27)
				)
				(justify mirror)
			)
		)
		(duplicate_pad_numbers_are_jumpers no)
		(fp_line
			(start -0.7874 0.4064)
			(end 0.7874 0.4064)
			(stroke
				(width 0.1524)
				(type default)
			)
			(layer "B.SilkS")
		)
		(fp_line
			(start 0.7874 0.4064)
			(end 0.7874 -0.4064)
			(stroke
				(width 0.1524)
				(type default)
			)
			(layer "B.SilkS")
		)
		(fp_line
			(start -0.7874 -0.4064)
			(end -0.7874 0.4064)
			(stroke
				(width 0.1524)
				(type default)
			)
			(layer "B.SilkS")
		)
		(fp_line
			(start 0.7874 -0.4064)
			(end -0.7874 -0.4064)
			(stroke
				(width 0.1524)
				(type default)
			)
			(layer "B.SilkS")
		)
		(fp_line
			(start -0.67945 0.3048)
			(end -0.120396 0.3048)
			(stroke
				(width 0.1)
				(type default)
			)
			(layer "B.Fab")
		)
		(fp_line
			(start -0.120396 0.3048)
			(end -0.120396 0.2794)
			(stroke
				(width 0.1)
				(type default)
			)
			(layer "B.Fab")
		)
		(fp_line
			(start 0.12065 0.3048)
			(end 0.67945 0.3048)
			(stroke
				(width 0.1)
				(type default)
			)
			(layer "B.Fab")
		)
		(fp_line
			(start 0.67945 0.3048)
			(end 0.67945 -0.305054)
			(stroke
				(width 0.1)
				(type default)
			)
			(layer "B.Fab")
		)
		(fp_line
			(start -0.120396 0.2794)
			(end 0.12065 0.2794)
			(stroke
				(width 0.1)
				(type default)
			)
			(layer "B.Fab")
		)
		(fp_line
			(start 0.12065 0.2794)
			(end 0.12065 0.3048)
			(stroke
				(width 0.1)
				(type default)
			)
			(layer "B.Fab")
		)
		(fp_line
			(start -0.12065 -0.2794)
			(end -0.12065 -0.3048)
			(stroke
				(width 0.1)
				(type default)
			)
			(layer "B.Fab")
		)
		(fp_line
			(start 0.12065 -0.2794)
			(end -0.12065 -0.2794)
			(stroke
				(width 0.1)
				(type default)
			)
			(layer "B.Fab")
		)
		(fp_line
			(start -0.67945 -0.3048)
			(end -0.67945 0.3048)
			(stroke
				(width 0.1)
				(type default)
			)
			(layer "B.Fab")
		)
		(fp_line
			(start -0.12065 -0.3048)
			(end -0.67945 -0.3048)
			(stroke
				(width 0.1)
				(type default)
			)
			(layer "B.Fab")
		)
		(fp_line
			(start 0.12065 -0.305054)
			(end 0.12065 -0.2794)
			(stroke
				(width 0.1)
				(type default)
			)
			(layer "B.Fab")
		)
		(fp_line
			(start 0.67945 -0.305054)
			(end 0.12065 -0.305054)
			(stroke
				(width 0.1)
				(type default)
			)
			(layer "B.Fab")
		)
		(pad "1" smd circle
			(at 0.40005 0 90)
			(size 0 0)
			(layers "B.Cu" "B.Mask" "B.Paste")
			(net "JTAG_MUX_CPU1_GTL_TDI")
		)
		(pad "2" smd circle
			(at -0.40005 0 90)
			(size 0 0)
			(layers "B.Cu" "B.Mask" "B.Paste")
			(net "JTAG_DBP_CPU1_GTL_R_TDI")
		)
	)
	(footprint ""
		(layer "B.Cu")
		(at 181.915308 -407.859484 -90)
		(property "Reference" "R4695"
			(at 0 0 90)
			(layer "B.SilkS")
			(hide yes)
			(effects
				(font
					(size 1.27 1.27)
				)
				(justify mirror)
			)
		)
		(property "Value" ""
			(at 0 0 90)
			(layer "B.Fab")
			(effects
				(font
					(size 1.27 1.27)
				)
				(justify mirror)
			)
		)
		(duplicate_pad_numbers_are_jumpers no)
		(fp_line
			(start -0.7874 0.4064)
			(end 0.7874 0.4064)
			(stroke
				(width 0.1524)
				(type default)
			)
			(layer "B.SilkS")
		)
		(fp_line
			(start 0.7874 0.4064)
			(end 0.7874 -0.4064)
			(stroke
				(width 0.1524)
				(type default)
			)
			(layer "B.SilkS")
		)
		(fp_line
			(start -0.7874 -0.4064)
			(end -0.7874 0.4064)
			(stroke
				(width 0.1524)
				(type default)
			)
			(layer "B.SilkS")
		)
		(fp_line
			(start 0.7874 -0.4064)
			(end -0.7874 -0.4064)
			(stroke
				(width 0.1524)
				(type default)
			)
			(layer "B.SilkS")
		)
		(fp_line
			(start -0.67945 0.3048)
			(end -0.120396 0.3048)
			(stroke
				(width 0.1)
				(type default)
			)
			(layer "B.Fab")
		)
		(fp_line
			(start -0.120396 0.3048)
			(end -0.120396 0.2794)
			(stroke
				(width 0.1)
				(type default)
			)
			(layer "B.Fab")
		)
		(fp_line
			(start 0.12065 0.3048)
			(end 0.67945 0.3048)
			(stroke
				(width 0.1)
				(type default)
			)
			(layer "B.Fab")
		)
		(fp_line
			(start 0.67945 0.3048)
			(end 0.67945 -0.305054)
			(stroke
				(width 0.1)
				(type default)
			)
			(layer "B.Fab")
		)
		(fp_line
			(start -0.120396 0.2794)
			(end 0.12065 0.2794)
			(stroke
				(width 0.1)
				(type default)
			)
			(layer "B.Fab")
		)
		(fp_line
			(start 0.12065 0.2794)
			(end 0.12065 0.3048)
			(stroke
				(width 0.1)
				(type default)
			)
			(layer "B.Fab")
		)
		(fp_line
			(start -0.12065 -0.2794)
			(end -0.12065 -0.3048)
			(stroke
				(width 0.1)
				(type default)
			)
			(layer "B.Fab")
		)
		(fp_line
			(start 0.12065 -0.2794)
			(end -0.12065 -0.2794)
			(stroke
				(width 0.1)
				(type default)
			)
			(layer "B.Fab")
		)
		(fp_line
			(start -0.67945 -0.3048)
			(end -0.67945 0.3048)
			(stroke
				(width 0.1)
				(type default)
			)
			(layer "B.Fab")
		)
		(fp_line
			(start -0.12065 -0.3048)
			(end -0.67945 -0.3048)
			(stroke
				(width 0.1)
				(type default)
			)
			(layer "B.Fab")
		)
		(fp_line
			(start 0.12065 -0.305054)
			(end 0.12065 -0.2794)
			(stroke
				(width 0.1)
				(type default)
			)
			(layer "B.Fab")
		)
		(fp_line
			(start 0.67945 -0.305054)
			(end 0.12065 -0.305054)
			(stroke
				(width 0.1)
				(type default)
			)
			(layer "B.Fab")
		)
		(pad "1" smd circle
			(at 0.40005 0 90)
			(size 0 0)
			(layers "B.Cu" "B.Mask" "B.Paste")
			(net "SMB_SML1_PMBUS_HSC_SCL")
		)
		(pad "2" smd circle
			(at -0.40005 0 90)
			(size 0 0)
			(layers "B.Cu" "B.Mask" "B.Paste")
			(net "SMB_SML1_PMBUS_HSC_MODULE_SCL")
		)
	)
)
